# SCM (Grand Teton) — schematic netlist excerpt (pin names and nets, part order shuffled) for the footprints in the layout excerpt that follows; sources: Cadence DE-HDL packaged netlist, KiCad conversion of 12092022_DA0F0TMDCD0_F0T_Management_Board_D_brd_V3_OCP.brd

C88  Q_CAP  0.1UF 25V 10% X7R  pkg 0402  page 16 : A = P3V3_AUX ; B = GND

X13  TP_TDR_4P_FTS  TP_TDR_4P_DIP EMPTY  pkg TH  page 60
  S1  = TDR_DIFF_100_TOP_DP
  P1  = GND_P1
  P2  = GND_P1
  S2  = TDR_DIFF_100_TOP_DN

(kicad_pcb
	(version 20260206)
	(generator "pcbnew")
	(generator_version "10.0")
	(general
		(thickness 1.6)
		(legacy_teardrops no)
	)
	(paper "A4")
	(title_block
		(title "12092022_DA0F0TMDCD0_F0T_Management_Board_D_brd_V3_OCP.brd")
		(comment 1 "Grand Teton / footprints 757-758 of 1440")
	)
	(layers
		(0 "F.Cu" signal "TOP")
		(4 "In1.Cu" signal "GND")
		(6 "In2.Cu" signal "IN1")
		(8 "In3.Cu" signal "GND1")
		(10 "In4.Cu" signal "IN2")
		(12 "In5.Cu" signal "VCC")
		(14 "In6.Cu" signal "VCC1")
		(16 "In7.Cu" signal "IN3")
		(18 "In8.Cu" signal "GND2")
		(20 "In9.Cu" signal "IN4")
		(22 "In10.Cu" signal "GND3")
		(2 "B.Cu" signal "BOTTOM")
		(9 "F.Adhes" user "F.Adhesive")
		(11 "B.Adhes" user "B.Adhesive")
		(13 "F.Paste" user "Package Geometry/Pastemask Top")
		(15 "B.Paste" user "Package Geometry/Pastemask Bottom")
		(5 "F.SilkS" user "Ref Des/Silkscreen Top")
		(7 "B.SilkS" user "Ref Des/Silkscreen Bottom")
		(1 "F.Mask" user "Board Geometry/Soldermask Top")
		(3 "B.Mask" user "Board Geometry/Soldermask Bottom")
		(17 "Dwgs.User" user "User.Drawings")
		(19 "Cmts.User" user "User.Comments")
		(21 "Eco1.User" user "User.Eco1")
		(23 "Eco2.User" user "User.Eco2")
		(25 "Edge.Cuts" user "Board Geometry/Outline")
		(27 "Margin" user)
		(31 "F.CrtYd" user "Package Geometry/Place Bound Top")
		(29 "B.CrtYd" user "Package Geometry/Place Bound Bottom")
		(35 "F.Fab" user "Ref Des/Assembly Top")
		(33 "B.Fab" user "Ref Des/Assembly Bottom")
	)
	(footprint ""
		(layer "B.Cu")
		(at 47.340774 -49.363122)
		(property "Reference" "C88"
			(at 0 0 0)
			(layer "B.SilkS")
			(hide yes)
			(effects
				(font
					(size 1.27 1.27)
				)
				(justify mirror)
			)
		)
		(property "Value" ""
			(at 0 0 0)
			(layer "B.Fab")
			(effects
				(font
					(size 1.27 1.27)
				)
				(justify mirror)
			)
		)
		(duplicate_pad_numbers_are_jumpers no)
		(fp_line
			(start -0.7874 -0.4064)
			(end -0.7874 0.4064)
			(stroke
				(width 0.1524)
				(type default)
			)
			(layer "B.SilkS")
		)
		(fp_line
			(start -0.7874 0.4064)
			(end 0.7874 0.4064)
			(stroke
				(width 0.1524)
				(type default)
			)
			(layer "B.SilkS")
		)
		(fp_line
			(start 0.7874 -0.4064)
			(end -0.7874 -0.4064)
			(stroke
				(width 0.1524)
				(type default)
			)
			(layer "B.SilkS")
		)
		(fp_line
			(start 0.7874 0.4064)
			(end 0.7874 -0.4064)
			(stroke
				(width 0.1524)
				(type default)
			)
			(layer "B.SilkS")
		)
		(fp_line
			(start -0.67945 -0.3048)
			(end -0.67945 0.3048)
			(stroke
				(width 0.1)
				(type default)
			)
			(layer "B.Fab")
		)
		(fp_line
			(start -0.67945 0.3048)
			(end -0.120396 0.3048)
			(stroke
				(width 0.1)
				(type default)
			)
			(layer "B.Fab")
		)
		(fp_line
			(start -0.12065 -0.3048)
			(end -0.67945 -0.3048)
			(stroke
				(width 0.1)
				(type default)
			)
			(layer "B.Fab")
		)
		(fp_line
			(start -0.12065 -0.2794)
			(end -0.12065 -0.3048)
			(stroke
				(width 0.1)
				(type default)
			)
			(layer "B.Fab")
		)
		(fp_line
			(start -0.120396 0.2794)
			(end 0.12065 0.2794)
			(stroke
				(width 0.1)
				(type default)
			)
			(layer "B.Fab")
		)
		(fp_line
			(start -0.120396 0.3048)
			(end -0.120396 0.2794)
			(stroke
				(width 0.1)
				(type default)
			)
			(layer "B.Fab")
		)
		(fp_line
			(start 0.12065 -0.305054)
			(end 0.12065 -0.2794)
			(stroke
				(width 0.1)
				(type default)
			)
			(layer "B.Fab")
		)
		(fp_line
			(start 0.12065 -0.2794)
			(end -0.12065 -0.2794)
			(stroke
				(width 0.1)
				(type default)
			)
			(layer "B.Fab")
		)
		(fp_line
			(start 0.12065 0.2794)
			(end 0.12065 0.3048)
			(stroke
				(width 0.1)
				(type default)
			)
			(layer "B.Fab")
		)
		(fp_line
			(start 0.12065 0.3048)
			(end 0.67945 0.3048)
			(stroke
				(width 0.1)
				(type default)
			)
			(layer "B.Fab")
		)
		(fp_line
			(start 0.67945 -0.305054)
			(end 0.12065 -0.305054)
			(stroke
				(width 0.1)
				(type default)
			)
			(layer "B.Fab")
		)
		(fp_line
			(start 0.67945 0.3048)
			(end 0.67945 -0.305054)
			(stroke
				(width 0.1)
				(type default)
			)
			(layer "B.Fab")
		)
		(pad "1" smd circle
			(at 0.40005 0 180)
			(size 0 0)
			(layers "B.Cu" "B.Mask" "B.Paste")
			(net "P3V3_AUX")
		)
		(pad "2" smd circle
			(at -0.40005 0 180)
			(size 0 0)
			(layers "B.Cu" "B.Mask" "B.Paste")
			(net "GND")
		)
	)
	(footprint ""
		(layer "B.Cu")
		(at 112.014 27.178 90)
		(property "Reference" "X13"
			(at 1.86563 3.2385 0)
			(unlocked yes)
			(layer "B.SilkS")
			(effects
				(font
					(size 0.7874 0.5842)
					(thickness 0.1524)
				)
				(justify left mirror)
			)
		)
		(property "Value" ""
			(at 0 0 90)
			(layer "B.Fab")
			(effects
				(font
					(size 1.27 1.27)
				)
				(justify mirror)
			)
		)
		(property "Device Type" "TP_TDR_4P_FTS_TH-TP_TDR_4P_DIPA"
			(at -1.30175 1.27 0)
			(unlocked yes)
			(layer "B.Fab")
			(hide yes)
			(effects
				(font
					(size 0.635 0.4064)
					(thickness 0.1524)
				)
				(justify mirror)
			)
		)
		(property "User Part Number" "N_A"
			(at -1.30175 1.27 0)
			(unlocked yes)
			(layer "Cmts.User")
			(hide yes)
			(effects
				(font
					(size 0.635 0.4064)
					(thickness 0.1524)
				)
				(justify mirror)
			)
		)
		(duplicate_pad_numbers_are_jumpers no)
		(fp_line
			(start 0 -1.27)
			(end 0 -0.635)
			(stroke
				(width 0.1524)
				(type default)
			)
			(layer "B.SilkS")
		)
		(fp_line
			(start -2.54 -1.27)
			(end 0 -1.27)
			(stroke
				(width 0.1524)
				(type default)
			)
			(layer "B.SilkS")
		)
		(fp_line
			(start -2.54 -1.1303)
			(end -2.54 -1.27)
			(stroke
				(width 0.1524)
				(type default)
			)
			(layer "B.SilkS")
		)
		(fp_line
			(start 0 0.635)
			(end 0 1.905)
			(stroke
				(width 0.1524)
				(type default)
			)
			(layer "B.SilkS")
		)
		(fp_line
			(start -2.54 1.4097)
			(end -2.54 1.1303)
			(stroke
				(width 0.1524)
				(type default)
			)
			(layer "B.SilkS")
		)
		(fp_line
			(start 0 3.175)
			(end 0 3.81)
			(stroke
				(width 0.1524)
				(type default)
			)
			(layer "B.SilkS")
		)
		(fp_line
			(start 0 3.81)
			(end -2.54 3.81)
			(stroke
				(width 0.1524)
				(type default)
			)
			(layer "B.SilkS")
		)
		(fp_line
			(start -2.54 3.81)
			(end -2.54 3.6703)
			(stroke
				(width 0.1524)
				(type default)
			)
			(layer "B.SilkS")
		)
		(fp_poly
			(pts
				(xy 0.761746 0) (xy 2.285746 -0.762) (xy 2.285746 0.762)
			)
			(stroke
				(width 0)
				(type default)
			)
			(fill yes)
			(layer "B.SilkS")
		)
		(fp_line
			(start 0 -1.27)
			(end 0 3.81)
			(stroke
				(width 0.1)
				(type default)
			)
			(layer "B.Fab")
		)
		(fp_line
			(start -2.54 -1.27)
			(end 0 -1.27)
			(stroke
				(width 0.1)
				(type default)
			)
			(layer "B.Fab")
		)
		(fp_line
			(start 0 3.81)
			(end -2.54 3.81)
			(stroke
				(width 0.1)
				(type default)
			)
			(layer "B.Fab")
		)
		(fp_line
			(start -2.54 3.81)
			(end -2.54 -1.27)
			(stroke
				(width 0.1)
				(type default)
			)
			(layer "B.Fab")
		)
		(fp_poly
			(pts
				(xy 0.761746 0) (xy 2.285746 -0.762) (xy 2.285746 0.762)
			)
			(stroke
				(width 0)
				(type default)
			)
			(fill yes)
			(layer "B.Fab")
		)
		(pad "1" thru_hole circle
			(at 0 0 270)
			(size 1.0033 1.0033)
			(drill 0.249936)
			(layers "*.Cu" "*.Mask")
			(remove_unused_layers no)
			(net "TDR_DIFF_100_TOP_DP")
			(clearance 0.10795)
			(padstack
				(mode front_inner_back)
				(layer "Inner"
					(shape circle)
					(size 0.8001 0.8001)
					(clearance 0.1524)
				)
				(layer "B.Cu"
					(shape circle)
					(size 1.0033 1.0033)
					(thermal_gap 0.10795)
					(clearance 0.10795)
				)
			)
		)
		(pad "2" thru_hole circle
			(at -2.54 0 270)
			(size 1.9939 1.9939)
			(drill 0.249936)
			(layers "*.Cu" "*.Mask")
			(remove_unused_layers no)
			(net "GND_P1")
			(clearance 0.10795)
			(padstack
				(mode front_inner_back)
				(layer "Inner"
					(shape circle)
					(size 0.8001 0.8001)
					(clearance 0.1524)
				)
				(layer "B.Cu"
					(shape circle)
					(size 1.9939 1.9939)
					(thermal_gap 0.10795)
					(clearance 0.10795)
				)
			)
		)
		(pad "3" thru_hole circle
			(at -2.54 2.54 270)
			(size 1.9939 1.9939)
			(drill 0.249936)
			(layers "*.Cu" "*.Mask")
			(remove_unused_layers no)
			(net "GND_P1")
			(clearance 0.10795)
			(padstack
				(mode front_inner_back)
				(layer "Inner"
					(shape circle)
					(size 0.8001 0.8001)
					(clearance 0.1524)
				)
				(layer "B.Cu"
					(shape circle)
					(size 1.9939 1.9939)
					(thermal_gap 0.10795)
					(clearance 0.10795)
				)
			)
		)
		(pad "4" thru_hole circle
			(at 0 2.54 270)
			(size 1.0033 1.0033)
			(drill 0.249936)
			(layers "*.Cu" "*.Mask")
			(remove_unused_layers no)
			(net "TDR_DIFF_100_TOP_DN")
			(clearance 0.10795)
			(padstack
				(mode front_inner_back)
				(layer "Inner"
					(shape circle)
					(size 0.8001 0.8001)
					(clearance 0.1524)
				)
				(layer "B.Cu"
					(shape circle)
					(size 1.0033 1.0033)
					(thermal_gap 0.10795)
					(clearance 0.10795)
				)
			)
		)
	)
)
